#ISCELL
  pure_quanta quanta_title_block_c *
  *
#CELL
  pure_quanta mosfet_n *
  page207_i236
#ISCELL
  logical_power universal_gnd *
  page207_i237
#ISCELL
  standard offpage *
  page207_i238
#ISCELL
  logical_power universal_power *
  page207_i240
#ISCELL
  logical_power universal_gnd *
  page207_i267
#CELL
  pure_quanta q_res *
  page207_i268
#ISCELL
  logical_power universal_gnd *
  page207_i269
#ISCELL
  logical_power universal_power *
  page207_i270
#CELL
  pure_quanta mosfet_nch_gds_esd_protected *
  page207_i272
#CELL
  pure_quanta q_res *
  page207_i273
#ISCELL
  logical_power universal_power *
  page207_i274
#CELL
  pure_quanta q_res *
  page207_i275
#ISCELL
  standard offpage *
  page207_i276
#CELL
  pure_quanta q_led *
  page207_i277
#CELL
  pure_quanta q_res *
  page207_i278
#CELL
  pure_quanta q_led *
  page207_i279
#CELL
  pure_quanta q_res *
  page207_i280
